(kicad_pcb
	(version 20260206)
	(generator "pcbnew")
	(generator_version "10.0")
	(general
		(thickness 1.21888)
		(legacy_teardrops no)
	)
	(paper "A4")
	(title_block
		(title "timecard-v9 — TimeCard-DC-V9_EXP.PcbDoc")
		(comment 1 "Time Appliance Project (Time Card) / footprints 235-240 of 402")
	)
	(layers
		(0 "F.Cu" signal "TOP")
		(4 "In1.Cu" signal "SGND")
		(6 "In2.Cu" signal "IN1")
		(8 "In3.Cu" signal "IN2")
		(10 "In4.Cu" signal "SGND1")
		(2 "B.Cu" signal "BOTTOM")
		(9 "F.Adhes" user "F.Adhesive")
		(11 "B.Adhes" user "B.Adhesive")
		(13 "F.Paste" user "Top Paste")
		(15 "B.Paste" user "Bottom Paste")
		(5 "F.SilkS" user "Top Overlay")
		(7 "B.SilkS" user "Bottom Overlay")
		(1 "F.Mask" user "Top Solder")
		(3 "B.Mask" user "Bottom Solder")
		(17 "Dwgs.User" user "User.Drawings")
		(19 "Cmts.User" user "User.Comments")
		(21 "Eco1.User" user "User.Eco1")
		(23 "Eco2.User" user "User.Eco2")
		(25 "Edge.Cuts" user)
		(27 "Margin" user)
		(31 "F.CrtYd" user "Top Courtyard")
		(29 "B.CrtYd" user "Bottom Courtyard")
		(35 "F.Fab" user "Top Component Center")
		(33 "B.Fab" user "Bottom Component Center")
	)
	(footprint "SamacSys:SOP50P310X90-8N"
		(layer "F.Cu")
		(at 76.1216 141.9162 180)
		(property "Reference" "U16"
			(at -0.2286 1.973079 0)
			(unlocked yes)
			(layer "F.SilkS")
			(effects
				(font
					(size 0.762 0.762)
					(thickness 0.2286)
				)
			)
		)
		(property "Value" "NC7WV125K8X"
			(at 6.207715 2.884671 180)
			(unlocked yes)
			(layer "F.SilkS")
			(hide yes)
			(effects
				(font
					(size 0.762 0.762)
					(thickness 0.2286)
				)
			)
		)
		(sheetname "01-USER_IO")
		(sheetfile "01-USER_IO.kicad_sch")
		(duplicate_pad_numbers_are_jumpers no)
		(fp_line
			(start 0.8 1)
			(end -0.8 1)
			(stroke
				(width 0.2)
				(type solid)
			)
			(layer "F.SilkS")
		)
		(fp_line
			(start 0.8 -1)
			(end 0.8 1)
			(stroke
				(width 0.2)
				(type solid)
			)
			(layer "F.SilkS")
		)
		(fp_line
			(start 0.8 -1)
			(end -0.8 -1)
			(stroke
				(width 0.2)
				(type solid)
			)
			(layer "F.SilkS")
		)
		(fp_line
			(start -0.8 -1)
			(end -0.8 1)
			(stroke
				(width 0.2)
				(type solid)
			)
			(layer "F.SilkS")
		)
		(fp_line
			(start -1.15 -1.25)
			(end -2 -1.25)
			(stroke
				(width 0.2)
				(type solid)
			)
			(layer "F.SilkS")
		)
		(pad "1" smd rect
			(at -1.575 -0.75 180)
			(size 0.85 0.3)
			(layers "F.Cu" "F.Mask" "F.Paste")
			(net "ANT4_IO_OUT")
		)
		(pad "2" smd rect
			(at -1.575 -0.25 180)
			(size 0.85 0.3)
			(layers "F.Cu" "F.Mask" "F.Paste")
			(net "ANT4_OUT")
		)
		(pad "3" smd rect
			(at -1.575 0.25 180)
			(size 0.85 0.3)
			(layers "F.Cu" "F.Mask" "F.Paste")
			(net "ANT4_IN")
		)
		(pad "4" smd rect
			(at -1.575 0.75 180)
			(size 0.85 0.3)
			(layers "F.Cu" "F.Mask" "F.Paste")
			(net "GND")
		)
		(pad "5" smd rect
			(at 1.575 0.75 180)
			(size 0.85 0.3)
			(layers "F.Cu" "F.Mask" "F.Paste")
			(net "NetR34_1")
		)
		(pad "6" smd rect
			(at 1.575 0.25 180)
			(size 0.85 0.3)
			(layers "F.Cu" "F.Mask" "F.Paste")
			(net "NetR34_1")
		)
		(pad "7" smd rect
			(at 1.575 -0.25 180)
			(size 0.85 0.3)
			(layers "F.Cu" "F.Mask" "F.Paste")
			(net "ANT4_IO_IN")
		)
		(pad "8" smd rect
			(at 1.575 -0.75 180)
			(size 0.85 0.3)
			(layers "F.Cu" "F.Mask" "F.Paste")
			(net "+3.3V")
		)
	)
	(footprint "Vault:RESC1005X40X25LL05T05"
		(layer "F.Cu")
		(at 84.65686 84.46371 180)
		(property "Reference" "R110"
			(at 2.97139 -0.426921 0)
			(unlocked yes)
			(layer "F.SilkS")
			(effects
				(font
					(size 0.762 0.762)
					(thickness 0.2286)
				)
			)
		)
		(property "Value" "DNI_4.7K_0402"
			(at -2.389361 9.43306 90)
			(unlocked yes)
			(layer "F.SilkS")
			(hide yes)
			(effects
				(font
					(size 0.762 0.762)
					(thickness 0.2032)
				)
			)
		)
		(sheetname "02-USER_IO_STATUS")
		(sheetfile "02-USER_IO_STATUS.kicad_sch")
		(duplicate_pad_numbers_are_jumpers no)
		(pad "1" smd rect
			(at -0.4 0 270)
			(size 0.45 0.45)
			(layers "F.Cu" "F.Mask" "F.Paste")
			(net "NetR108_2")
		)
		(pad "2" smd rect
			(at 0.4 0 270)
			(size 0.45 0.45)
			(layers "F.Cu" "F.Mask" "F.Paste")
			(net "GND")
		)
	)
	(footprint "Vault:RESC1005X40X25LL05T10"
		(layer "F.Cu")
		(at 122.9216 77.4162 180)
		(property "Reference" "R173"
			(at -2.4032 0.073079 0)
			(unlocked yes)
			(layer "F.SilkS")
			(effects
				(font
					(size 0.762 0.762)
					(thickness 0.2032)
				)
			)
		)
		(property "Value" "DNI_49.9_1%_0402"
			(at -2.579871 11.71832 90)
			(unlocked yes)
			(layer "F.SilkS")
			(hide yes)
			(effects
				(font
					(size 0.762 0.762)
					(thickness 0.2032)
				)
			)
		)
		(sheetname "11-M2_RCB_MUX")
		(sheetfile "11-M2_RCB_MUX.kicad_sch")
		(duplicate_pad_numbers_are_jumpers no)
		(pad "1" smd rect
			(at -0.375 0 270)
			(size 0.45 0.5)
			(layers "F.Cu" "F.Mask" "F.Paste")
			(net "GPS1_PIN12")
		)
		(pad "2" smd rect
			(at 0.375 0 270)
			(size 0.45 0.5)
			(layers "F.Cu" "F.Mask" "F.Paste")
			(net "RCB_GPS1_PIN12")
		)
	)
	(footprint "IS32FL3207:IS32FL3207"
		(layer "F.Cu")
		(at 93.70686 86.56371)
		(property "Reference" "U6"
			(at -2.271395 -3.723079 0)
			(unlocked yes)
			(layer "F.SilkS")
			(effects
				(font
					(size 0.762 0.762)
					(thickness 0.2286)
				)
			)
		)
		(property "Value" "IS32FL3207"
			(at 4.17596 4.662671 0)
			(unlocked yes)
			(layer "F.SilkS")
			(hide yes)
			(effects
				(font
					(size 0.762 0.762)
					(thickness 0.2286)
				)
			)
		)
		(sheetname "02-USER_IO_STATUS")
		(sheetfile "02-USER_IO_STATUS.kicad_sch")
		(duplicate_pad_numbers_are_jumpers no)
		(fp_line
			(start -2.65 -2.65)
			(end -2.04999 -2.65)
			(stroke
				(width 0.2)
				(type solid)
			)
			(layer "F.SilkS")
		)
		(fp_line
			(start -2.65 -2.05)
			(end -2.65 -2.65)
			(stroke
				(width 0.2)
				(type solid)
			)
			(layer "F.SilkS")
		)
		(fp_line
			(start -2.65 2.65)
			(end -2.65 2.05)
			(stroke
				(width 0.2)
				(type solid)
			)
			(layer "F.SilkS")
		)
		(fp_line
			(start -2.65 2.65)
			(end -2.04999 2.65)
			(stroke
				(width 0.2)
				(type solid)
			)
			(layer "F.SilkS")
		)
		(fp_line
			(start 2.05001 -2.65)
			(end 2.65 -2.65)
			(stroke
				(width 0.2)
				(type solid)
			)
			(layer "F.SilkS")
		)
		(fp_line
			(start 2.05001 2.65)
			(end 2.65 2.65)
			(stroke
				(width 0.2)
				(type solid)
			)
			(layer "F.SilkS")
		)
		(fp_line
			(start 2.65 -2.05)
			(end 2.65 -2.65)
			(stroke
				(width 0.2)
				(type solid)
			)
			(layer "F.SilkS")
		)
		(fp_line
			(start 2.65 2.65)
			(end 2.65 2.05)
			(stroke
				(width 0.2)
				(type solid)
			)
			(layer "F.SilkS")
		)
		(fp_circle
			(center -3.29999 -2.5)
			(end -3.29999 -2.625)
			(stroke
				(width 0.25)
				(type solid)
			)
			(fill no)
			(layer "F.SilkS")
		)
		(pad "1" smd rect
			(at -2.32499 -1.5 90)
			(size 0.26 0.9)
			(layers "F.Cu" "F.Mask" "F.Paste")
			(net "NetR40_2")
		)
		(pad "2" smd rect
			(at -2.32499 -1 90)
			(size 0.26 0.9)
			(layers "F.Cu" "F.Mask" "F.Paste")
			(net "NetR108_2")
		)
		(pad "3" smd rect
			(at -2.32499 -0.5 90)
			(size 0.26 0.9)
			(layers "F.Cu" "F.Mask" "F.Paste")
			(net "+3.3V")
		)
		(pad "4" smd rect
			(at -2.32499 0 90)
			(size 0.26 0.9)
			(layers "F.Cu" "F.Mask" "F.Paste")
			(net "GND")
		)
		(pad "5" smd rect
			(at -2.32499 0.5 90)
			(size 0.26 0.9)
			(layers "F.Cu" "F.Mask" "F.Paste")
			(net "NetR41_2")
		)
		(pad "6" smd rect
			(at -2.32499 1 90)
			(size 0.26 0.9)
			(layers "F.Cu" "F.Mask" "F.Paste")
			(net "SENS_I2C_SDA")
		)
		(pad "7" smd rect
			(at -2.32499 1.5 90)
			(size 0.26 0.9)
			(layers "F.Cu" "F.Mask" "F.Paste")
			(net "SENS_I2C_SCL")
		)
		(pad "8" smd rect
			(at -1.5 2.32499)
			(size 0.26 0.9)
			(layers "F.Cu" "F.Mask" "F.Paste")
			(net "NetD13_4")
		)
		(pad "9" smd rect
			(at -1 2.32499)
			(size 0.26 0.9)
			(layers "F.Cu" "F.Mask" "F.Paste")
			(net "NetD13_3")
		)
		(pad "10" smd rect
			(at -0.5 2.32499)
			(size 0.26 0.9)
			(layers "F.Cu" "F.Mask" "F.Paste")
			(net "NetD13_2")
		)
		(pad "11" smd rect
			(at 0 2.32499)
			(size 0.26 0.9)
			(layers "F.Cu" "F.Mask" "F.Paste")
			(net "GND")
		)
		(pad "12" smd rect
			(at 0.5 2.32499)
			(size 0.26 0.9)
			(layers "F.Cu" "F.Mask" "F.Paste")
			(net "NetD14_4")
		)
		(pad "13" smd rect
			(at 1 2.32499)
			(size 0.26 0.9)
			(layers "F.Cu" "F.Mask" "F.Paste")
			(net "NetD14_3")
		)
		(pad "14" smd rect
			(at 1.5 2.32499)
			(size 0.26 0.9)
			(layers "F.Cu" "F.Mask" "F.Paste")
			(net "NetD14_2")
		)
		(pad "15" smd rect
			(at 2.32501 1.5 90)
			(size 0.26 0.9)
			(layers "F.Cu" "F.Mask" "F.Paste")
			(net "NetD15_4")
		)
		(pad "16" smd rect
			(at 2.32501 1 90)
			(size 0.26 0.9)
			(layers "F.Cu" "F.Mask" "F.Paste")
			(net "NetD15_3")
		)
		(pad "17" smd rect
			(at 2.32501 0.5 90)
			(size 0.26 0.9)
			(layers "F.Cu" "F.Mask" "F.Paste")
			(net "NetD15_2")
		)
		(pad "18" smd rect
			(at 2.32501 0 90)
			(size 0.26 0.9)
			(layers "F.Cu" "F.Mask" "F.Paste")
			(net "GND")
		)
		(pad "19" smd rect
			(at 2.32501 -0.5 90)
			(size 0.26 0.9)
			(layers "F.Cu" "F.Mask" "F.Paste")
			(net "NetD16_4")
		)
		(pad "20" smd rect
			(at 2.32501 -1 90)
			(size 0.26 0.9)
			(layers "F.Cu" "F.Mask" "F.Paste")
			(net "NetD16_3")
		)
		(pad "21" smd rect
			(at 2.32501 -1.5 90)
			(size 0.26 0.9)
			(layers "F.Cu" "F.Mask" "F.Paste")
			(net "NetD16_2")
		)
		(pad "22" smd rect
			(at 1.50001 -2.325)
			(size 0.26 0.9)
			(layers "F.Cu" "F.Mask" "F.Paste")
			(net "NetD17_4")
		)
		(pad "23" smd rect
			(at 1.00001 -2.325)
			(size 0.26 0.9)
			(layers "F.Cu" "F.Mask" "F.Paste")
			(net "NetD17_3")
		)
		(pad "24" smd rect
			(at 0.50001 -2.325)
			(size 0.26 0.9)
			(layers "F.Cu" "F.Mask" "F.Paste")
			(net "NetD17_2")
		)
		(pad "25" smd rect
			(at 0 -2.325)
			(size 0.26 0.9)
			(layers "F.Cu" "F.Mask" "F.Paste")
			(net "GND")
		)
		(pad "26" smd rect
			(at -0.49999 -2.325)
			(size 0.26 0.9)
			(layers "F.Cu" "F.Mask" "F.Paste")
			(net "NetD18_4")
		)
		(pad "27" smd rect
			(at -0.99999 -2.325)
			(size 0.26 0.9)
			(layers "F.Cu" "F.Mask" "F.Paste")
			(net "NetD18_3")
		)
		(pad "28" smd rect
			(at -1.49999 -2.325)
			(size 0.26 0.9)
			(layers "F.Cu" "F.Mask" "F.Paste")
			(net "NetD18_2")
		)
		(pad "29" smd rect
			(at 0 0)
			(size 3.25 3.25)
			(layers "F.Cu" "F.Mask" "F.Paste")
			(net "GND")
		)
	)
	(footprint "SamacSys:155124M173200"
		(layer "F.Cu")
		(at 67.4466 128.4162 90)
		(property "Reference" "D17"
			(at -0.3286 1.448069 270)
			(unlocked yes)
			(layer "F.SilkS")
			(effects
				(font
					(size 0.762 0.762)
					(thickness 0.2286)
				)
			)
		)
		(property "Value" "155124M173200"
			(at 7.1471 2.605271 90)
			(unlocked yes)
			(layer "F.SilkS")
			(hide yes)
			(effects
				(font
					(size 0.762 0.762)
					(thickness 0.2286)
				)
			)
		)
		(sheetname "02-USER_IO_STATUS")
		(sheetfile "02-USER_IO_STATUS.kicad_sch")
		(duplicate_pad_numbers_are_jumpers no)
		(fp_line
			(start -0.8 0.5)
			(end 0.8 0.5)
			(stroke
				(width 0.1)
				(type solid)
			)
			(layer "F.SilkS")
		)
		(fp_arc
			(start -2 -0.1)
			(mid -1.95 -0.05)
			(end -2 0)
			(stroke
				(width 0.381)
				(type solid)
			)
			(layer "F.SilkS")
		)
		(fp_arc
			(start -2 0)
			(mid -2.05 -0.05)
			(end -2 -0.1)
			(stroke
				(width 0.381)
				(type solid)
			)
			(layer "F.SilkS")
		)
		(pad "1" smd rect
			(at -1.4 0 180)
			(size 0.9 0.6)
			(layers "F.Cu" "F.Mask" "F.Paste")
			(net "+3.3V")
		)
		(pad "2" smd rect
			(at -0.45 -0.325 90)
			(size 0.6 0.55)
			(layers "F.Cu" "F.Mask" "F.Paste")
			(net "NetD17_2")
		)
		(pad "3" smd rect
			(at 0.45 -0.325 90)
			(size 0.6 0.55)
			(layers "F.Cu" "F.Mask" "F.Paste")
			(net "NetD17_3")
		)
		(pad "4" smd rect
			(at 1.4 0 180)
			(size 0.9 0.6)
			(layers "F.Cu" "F.Mask" "F.Paste")
			(net "NetD17_4")
		)
	)
	(footprint "SA53:SA53_Header"
		(locked yes)
		(layer "F.Cu")
		(at 130.25657 114.79691 180)
		(property "Reference" "J31"
			(at 3.046085 -8.854759 180)
			(unlocked yes)
			(layer "F.SilkS")
			(effects
				(font
					(size 0.762 0.762)
					(thickness 0.2286)
				)
			)
		)
		(property "Value" "SA53_Header"
			(at 7.655515 4.548351 180)
			(unlocked yes)
			(layer "F.SilkS")
			(hide yes)
			(effects
				(font
					(size 0.762 0.762)
					(thickness 0.2286)
				)
			)
		)
		(sheetname "06-MAC")
		(sheetfile "06-MAC.kicad_sch")
		(duplicate_pad_numbers_are_jumpers no)
		(fp_circle
			(center 6.42 0.072)
			(end 6.42 0.199)
			(stroke
				(width 0.254)
				(type solid)
			)
			(fill no)
			(layer "F.SilkS")
		)
		(pad "1" smd rect
			(at 5 0.072 270)
			(size 0.25 1.8)
			(layers "F.Cu" "F.Mask" "F.Paste")
			(net "MAC_PPS_IN1+")
		)
		(pad "2" smd rect
			(at 1 0.072 270)
			(size 0.25 1.8)
			(layers "F.Cu" "F.Mask" "F.Paste")
			(net "MAC_USB+")
		)
		(pad "3" smd rect
			(at 5 -0.436 270)
			(size 0.25 1.8)
			(layers "F.Cu" "F.Mask" "F.Paste")
			(net "MAC_PPS_IN1-")
		)
		(pad "4" smd rect
			(at 1 -0.436 270)
			(size 0.25 1.8)
			(layers "F.Cu" "F.Mask" "F.Paste")
			(net "MAC_USB-")
		)
		(pad "5" smd rect
			(at 5 -0.944 270)
			(size 0.25 1.8)
			(layers "F.Cu" "F.Mask" "F.Paste")
			(net "MAC_PPS_IN0+")
		)
		(pad "6" smd rect
			(at 1 -0.944 270)
			(size 0.25 1.8)
			(layers "F.Cu" "F.Mask" "F.Paste")
			(net "MAC_USB_PWR")
		)
		(pad "7" smd rect
			(at 5 -1.452 270)
			(size 0.25 1.8)
			(layers "F.Cu" "F.Mask" "F.Paste")
			(net "MAC_PPS_IN0-")
		)
		(pad "8" smd rect
			(at 1 -1.452 270)
			(size 0.25 1.8)
			(layers "F.Cu" "F.Mask" "F.Paste")
			(net "GND")
		)
		(pad "9" smd rect
			(at 5 -1.96 270)
			(size 0.25 1.8)
			(layers "F.Cu" "F.Mask" "F.Paste")
			(net "GND")
		)
		(pad "10" smd rect
			(at 1 -1.96 270)
			(size 0.25 1.8)
			(layers "F.Cu" "F.Mask" "F.Paste")
		)
		(pad "11" smd rect
			(at 5 -2.468 270)
			(size 0.25 1.8)
			(layers "F.Cu" "F.Mask" "F.Paste")
		)
		(pad "12" smd rect
			(at 1 -2.468 270)
			(size 0.25 1.8)
			(layers "F.Cu" "F.Mask" "F.Paste")
		)
		(pad "13" smd rect
			(at 5 -2.976 270)
			(size 0.25 1.8)
			(layers "F.Cu" "F.Mask" "F.Paste")
		)
		(pad "14" smd rect
			(at 1 -2.976 270)
			(size 0.25 1.8)
			(layers "F.Cu" "F.Mask" "F.Paste")
		)
		(pad "15" smd rect
			(at 5 -3.484 270)
			(size 0.25 1.8)
			(layers "F.Cu" "F.Mask" "F.Paste")
			(net "GND")
		)
		(pad "16" smd rect
			(at 1 -3.484 270)
			(size 0.25 1.8)
			(layers "F.Cu" "F.Mask" "F.Paste")
		)
		(pad "17" smd rect
			(at 5 -3.992 270)
			(size 0.25 1.8)
			(layers "F.Cu" "F.Mask" "F.Paste")
			(net "MAC_PPS_OUT+")
		)
		(pad "18" smd rect
			(at 1 -3.992 270)
			(size 0.25 1.8)
			(layers "F.Cu" "F.Mask" "F.Paste")
		)
		(pad "19" smd rect
			(at 5 -4.5 270)
			(size 0.25 1.8)
			(layers "F.Cu" "F.Mask" "F.Paste")
			(net "MAC_PPS_OUT-")
		)
		(pad "20" smd rect
			(at 1 -4.5 270)
			(size 0.25 1.8)
			(layers "F.Cu" "F.Mask" "F.Paste")
			(net "MAC_ALARM")
		)
		(zone
			(layer "F.Cu")
			(hatch edge 0.5)
			(connect_pads
				(clearance 0)
			)
			(min_thickness 0.25)
			(keepout
				(tracks allowed)
				(vias allowed)
				(pads allowed)
				(copperpour not_allowed)
				(footprints allowed)
			)
			(placement
				(enabled no)
				(sheetname "")
			)
			(fill
				(thermal_gap 0.5)
				(thermal_bridge_width 0.5)
				(island_removal_mode 0)
			)
			(polygon
				(pts
					(xy 123.58908 121.8662) (xy 123.58909 111.8662) (xy 131.08909 111.8662) (xy 131.08908 121.8662)
				)
			)
		)
	)
)
